(kicad_pcb
	(version 20260206)
	(generator "pcbnew")
	(generator_version "10.0")
	(general
		(thickness 1.6)
		(legacy_teardrops no)
	)
	(paper "A4")
	(title_block
		(title "12092022_DA0F0TMDCD0_F0T_Management_Board_D_brd_V3_OCP.brd")
		(comment 1 "Grand Teton / footprints 1166-1171 of 1440")
	)
	(layers
		(0 "F.Cu" signal "TOP")
		(4 "In1.Cu" signal "GND")
		(6 "In2.Cu" signal "IN1")
		(8 "In3.Cu" signal "GND1")
		(10 "In4.Cu" signal "IN2")
		(12 "In5.Cu" signal "VCC")
		(14 "In6.Cu" signal "VCC1")
		(16 "In7.Cu" signal "IN3")
		(18 "In8.Cu" signal "GND2")
		(20 "In9.Cu" signal "IN4")
		(22 "In10.Cu" signal "GND3")
		(2 "B.Cu" signal "BOTTOM")
		(9 "F.Adhes" user "F.Adhesive")
		(11 "B.Adhes" user "B.Adhesive")
		(13 "F.Paste" user "Package Geometry/Pastemask Top")
		(15 "B.Paste" user "Package Geometry/Pastemask Bottom")
		(5 "F.SilkS" user "Ref Des/Silkscreen Top")
		(7 "B.SilkS" user "Ref Des/Silkscreen Bottom")
		(1 "F.Mask" user "Board Geometry/Soldermask Top")
		(3 "B.Mask" user "Board Geometry/Soldermask Bottom")
		(17 "Dwgs.User" user "User.Drawings")
		(19 "Cmts.User" user "User.Comments")
		(21 "Eco1.User" user "User.Eco1")
		(23 "Eco2.User" user "User.Eco2")
		(25 "Edge.Cuts" user "Board Geometry/Outline")
		(27 "Margin" user)
		(31 "F.CrtYd" user "Package Geometry/Place Bound Top")
		(29 "B.CrtYd" user "Package Geometry/Place Bound Bottom")
		(35 "F.Fab" user "Ref Des/Assembly Top")
		(33 "B.Fab" user "Ref Des/Assembly Bottom")
	)
	(footprint ""
		(layer "B.Cu")
		(at 61.063378 -46.426628)
		(property "Reference" "C76"
			(at 0 0 0)
			(layer "B.SilkS")
			(hide yes)
			(effects
				(font
					(size 1.27 1.27)
				)
				(justify mirror)
			)
		)
		(property "Value" ""
			(at 0 0 0)
			(layer "B.Fab")
			(effects
				(font
					(size 1.27 1.27)
				)
				(justify mirror)
			)
		)
		(duplicate_pad_numbers_are_jumpers no)
		(fp_line
			(start -0.7874 -0.4064)
			(end -0.7874 0.4064)
			(stroke
				(width 0.1524)
				(type default)
			)
			(layer "B.SilkS")
		)
		(fp_line
			(start -0.7874 0.4064)
			(end 0.7874 0.4064)
			(stroke
				(width 0.1524)
				(type default)
			)
			(layer "B.SilkS")
		)
		(fp_line
			(start 0.7874 -0.4064)
			(end -0.7874 -0.4064)
			(stroke
				(width 0.1524)
				(type default)
			)
			(layer "B.SilkS")
		)
		(fp_line
			(start 0.7874 0.4064)
			(end 0.7874 -0.4064)
			(stroke
				(width 0.1524)
				(type default)
			)
			(layer "B.SilkS")
		)
		(fp_line
			(start -0.67945 -0.3048)
			(end -0.67945 0.3048)
			(stroke
				(width 0.1)
				(type default)
			)
			(layer "B.Fab")
		)
		(fp_line
			(start -0.67945 0.3048)
			(end -0.120396 0.3048)
			(stroke
				(width 0.1)
				(type default)
			)
			(layer "B.Fab")
		)
		(fp_line
			(start -0.12065 -0.3048)
			(end -0.67945 -0.3048)
			(stroke
				(width 0.1)
				(type default)
			)
			(layer "B.Fab")
		)
		(fp_line
			(start -0.12065 -0.2794)
			(end -0.12065 -0.3048)
			(stroke
				(width 0.1)
				(type default)
			)
			(layer "B.Fab")
		)
		(fp_line
			(start -0.120396 0.2794)
			(end 0.12065 0.2794)
			(stroke
				(width 0.1)
				(type default)
			)
			(layer "B.Fab")
		)
		(fp_line
			(start -0.120396 0.3048)
			(end -0.120396 0.2794)
			(stroke
				(width 0.1)
				(type default)
			)
			(layer "B.Fab")
		)
		(fp_line
			(start 0.12065 -0.305054)
			(end 0.12065 -0.2794)
			(stroke
				(width 0.1)
				(type default)
			)
			(layer "B.Fab")
		)
		(fp_line
			(start 0.12065 -0.2794)
			(end -0.12065 -0.2794)
			(stroke
				(width 0.1)
				(type default)
			)
			(layer "B.Fab")
		)
		(fp_line
			(start 0.12065 0.2794)
			(end 0.12065 0.3048)
			(stroke
				(width 0.1)
				(type default)
			)
			(layer "B.Fab")
		)
		(fp_line
			(start 0.12065 0.3048)
			(end 0.67945 0.3048)
			(stroke
				(width 0.1)
				(type default)
			)
			(layer "B.Fab")
		)
		(fp_line
			(start 0.67945 -0.305054)
			(end 0.12065 -0.305054)
			(stroke
				(width 0.1)
				(type default)
			)
			(layer "B.Fab")
		)
		(fp_line
			(start 0.67945 0.3048)
			(end 0.67945 -0.305054)
			(stroke
				(width 0.1)
				(type default)
			)
			(layer "B.Fab")
		)
		(pad "1" smd circle
			(at 0.40005 0 180)
			(size 0 0)
			(layers "B.Cu" "B.Mask" "B.Paste")
			(net "P1V2_AUX")
		)
		(pad "2" smd circle
			(at -0.40005 0 180)
			(size 0 0)
			(layers "B.Cu" "B.Mask" "B.Paste")
			(net "GND")
		)
	)
	(footprint ""
		(layer "B.Cu")
		(at 39.0652 -106.3752 -90)
		(property "Reference" "R73"
			(at 0 0 90)
			(layer "B.SilkS")
			(hide yes)
			(effects
				(font
					(size 1.27 1.27)
				)
				(justify mirror)
			)
		)
		(property "Value" ""
			(at 0 0 90)
			(layer "B.Fab")
			(effects
				(font
					(size 1.27 1.27)
				)
				(justify mirror)
			)
		)
		(duplicate_pad_numbers_are_jumpers no)
		(fp_line
			(start -0.7874 0.4064)
			(end 0.7874 0.4064)
			(stroke
				(width 0.1524)
				(type default)
			)
			(layer "B.SilkS")
		)
		(fp_line
			(start 0.7874 0.4064)
			(end 0.7874 -0.4064)
			(stroke
				(width 0.1524)
				(type default)
			)
			(layer "B.SilkS")
		)
		(fp_line
			(start -0.7874 -0.4064)
			(end -0.7874 0.4064)
			(stroke
				(width 0.1524)
				(type default)
			)
			(layer "B.SilkS")
		)
		(fp_line
			(start 0.7874 -0.4064)
			(end -0.7874 -0.4064)
			(stroke
				(width 0.1524)
				(type default)
			)
			(layer "B.SilkS")
		)
		(fp_line
			(start -0.67945 0.3048)
			(end -0.120396 0.3048)
			(stroke
				(width 0.1)
				(type default)
			)
			(layer "B.Fab")
		)
		(fp_line
			(start -0.120396 0.3048)
			(end -0.120396 0.2794)
			(stroke
				(width 0.1)
				(type default)
			)
			(layer "B.Fab")
		)
		(fp_line
			(start 0.12065 0.3048)
			(end 0.67945 0.3048)
			(stroke
				(width 0.1)
				(type default)
			)
			(layer "B.Fab")
		)
		(fp_line
			(start 0.67945 0.3048)
			(end 0.67945 -0.305054)
			(stroke
				(width 0.1)
				(type default)
			)
			(layer "B.Fab")
		)
		(fp_line
			(start -0.120396 0.2794)
			(end 0.12065 0.2794)
			(stroke
				(width 0.1)
				(type default)
			)
			(layer "B.Fab")
		)
		(fp_line
			(start 0.12065 0.2794)
			(end 0.12065 0.3048)
			(stroke
				(width 0.1)
				(type default)
			)
			(layer "B.Fab")
		)
		(fp_line
			(start -0.12065 -0.2794)
			(end -0.12065 -0.3048)
			(stroke
				(width 0.1)
				(type default)
			)
			(layer "B.Fab")
		)
		(fp_line
			(start 0.12065 -0.2794)
			(end -0.12065 -0.2794)
			(stroke
				(width 0.1)
				(type default)
			)
			(layer "B.Fab")
		)
		(fp_line
			(start -0.67945 -0.3048)
			(end -0.67945 0.3048)
			(stroke
				(width 0.1)
				(type default)
			)
			(layer "B.Fab")
		)
		(fp_line
			(start -0.12065 -0.3048)
			(end -0.67945 -0.3048)
			(stroke
				(width 0.1)
				(type default)
			)
			(layer "B.Fab")
		)
		(fp_line
			(start 0.12065 -0.305054)
			(end 0.12065 -0.2794)
			(stroke
				(width 0.1)
				(type default)
			)
			(layer "B.Fab")
		)
		(fp_line
			(start 0.67945 -0.305054)
			(end 0.12065 -0.305054)
			(stroke
				(width 0.1)
				(type default)
			)
			(layer "B.Fab")
		)
		(pad "1" smd circle
			(at 0.40005 0 90)
			(size 0 0)
			(layers "B.Cu" "B.Mask" "B.Paste")
			(net "P3V3_AUX")
		)
		(pad "2" smd circle
			(at -0.40005 0 90)
			(size 0 0)
			(layers "B.Cu" "B.Mask" "B.Paste")
			(net "SGPIO_LD_1")
		)
	)
	(footprint ""
		(layer "B.Cu")
		(at 83.16722 -48.618394)
		(property "Reference" "R342"
			(at 0 0 0)
			(layer "B.SilkS")
			(hide yes)
			(effects
				(font
					(size 1.27 1.27)
				)
				(justify mirror)
			)
		)
		(property "Value" ""
			(at 0 0 0)
			(layer "B.Fab")
			(effects
				(font
					(size 1.27 1.27)
				)
				(justify mirror)
			)
		)
		(duplicate_pad_numbers_are_jumpers no)
		(fp_line
			(start -0.7874 -0.4064)
			(end -0.7874 0.4064)
			(stroke
				(width 0.1524)
				(type default)
			)
			(layer "B.SilkS")
		)
		(fp_line
			(start -0.7874 0.4064)
			(end 0.7874 0.4064)
			(stroke
				(width 0.1524)
				(type default)
			)
			(layer "B.SilkS")
		)
		(fp_line
			(start 0.7874 -0.4064)
			(end -0.7874 -0.4064)
			(stroke
				(width 0.1524)
				(type default)
			)
			(layer "B.SilkS")
		)
		(fp_line
			(start 0.7874 0.4064)
			(end 0.7874 -0.4064)
			(stroke
				(width 0.1524)
				(type default)
			)
			(layer "B.SilkS")
		)
		(fp_line
			(start -0.67945 -0.3048)
			(end -0.67945 0.3048)
			(stroke
				(width 0.1)
				(type default)
			)
			(layer "B.Fab")
		)
		(fp_line
			(start -0.67945 0.3048)
			(end -0.120396 0.3048)
			(stroke
				(width 0.1)
				(type default)
			)
			(layer "B.Fab")
		)
		(fp_line
			(start -0.12065 -0.3048)
			(end -0.67945 -0.3048)
			(stroke
				(width 0.1)
				(type default)
			)
			(layer "B.Fab")
		)
		(fp_line
			(start -0.12065 -0.2794)
			(end -0.12065 -0.3048)
			(stroke
				(width 0.1)
				(type default)
			)
			(layer "B.Fab")
		)
		(fp_line
			(start -0.120396 0.2794)
			(end 0.12065 0.2794)
			(stroke
				(width 0.1)
				(type default)
			)
			(layer "B.Fab")
		)
		(fp_line
			(start -0.120396 0.3048)
			(end -0.120396 0.2794)
			(stroke
				(width 0.1)
				(type default)
			)
			(layer "B.Fab")
		)
		(fp_line
			(start 0.12065 -0.305054)
			(end 0.12065 -0.2794)
			(stroke
				(width 0.1)
				(type default)
			)
			(layer "B.Fab")
		)
		(fp_line
			(start 0.12065 -0.2794)
			(end -0.12065 -0.2794)
			(stroke
				(width 0.1)
				(type default)
			)
			(layer "B.Fab")
		)
		(fp_line
			(start 0.12065 0.2794)
			(end 0.12065 0.3048)
			(stroke
				(width 0.1)
				(type default)
			)
			(layer "B.Fab")
		)
		(fp_line
			(start 0.12065 0.3048)
			(end 0.67945 0.3048)
			(stroke
				(width 0.1)
				(type default)
			)
			(layer "B.Fab")
		)
		(fp_line
			(start 0.67945 -0.305054)
			(end 0.12065 -0.305054)
			(stroke
				(width 0.1)
				(type default)
			)
			(layer "B.Fab")
		)
		(fp_line
			(start 0.67945 0.3048)
			(end 0.67945 -0.305054)
			(stroke
				(width 0.1)
				(type default)
			)
			(layer "B.Fab")
		)
		(pad "1" smd circle
			(at 0.40005 0 180)
			(size 0 0)
			(layers "B.Cu" "B.Mask" "B.Paste")
			(net "GND")
		)
		(pad "2" smd circle
			(at -0.40005 0 180)
			(size 0 0)
			(layers "B.Cu" "B.Mask" "B.Paste")
			(net "M_BMC_DDR4_MRAS_N")
		)
	)
	(footprint ""
		(layer "B.Cu")
		(at 26.3652 -97.282 -90)
		(property "Reference" "C152"
			(at 0 0 90)
			(layer "B.SilkS")
			(hide yes)
			(effects
				(font
					(size 1.27 1.27)
				)
				(justify mirror)
			)
		)
		(property "Value" ""
			(at 0 0 90)
			(layer "B.Fab")
			(effects
				(font
					(size 1.27 1.27)
				)
				(justify mirror)
			)
		)
		(duplicate_pad_numbers_are_jumpers no)
		(fp_line
			(start -0.7874 0.4064)
			(end 0.7874 0.4064)
			(stroke
				(width 0.1524)
				(type default)
			)
			(layer "B.SilkS")
		)
		(fp_line
			(start 0.7874 0.4064)
			(end 0.7874 -0.4064)
			(stroke
				(width 0.1524)
				(type default)
			)
			(layer "B.SilkS")
		)
		(fp_line
			(start -0.7874 -0.4064)
			(end -0.7874 0.4064)
			(stroke
				(width 0.1524)
				(type default)
			)
			(layer "B.SilkS")
		)
		(fp_line
			(start 0.7874 -0.4064)
			(end -0.7874 -0.4064)
			(stroke
				(width 0.1524)
				(type default)
			)
			(layer "B.SilkS")
		)
		(fp_line
			(start -0.67945 0.3048)
			(end -0.120396 0.3048)
			(stroke
				(width 0.1)
				(type default)
			)
			(layer "B.Fab")
		)
		(fp_line
			(start -0.120396 0.3048)
			(end -0.120396 0.2794)
			(stroke
				(width 0.1)
				(type default)
			)
			(layer "B.Fab")
		)
		(fp_line
			(start 0.12065 0.3048)
			(end 0.67945 0.3048)
			(stroke
				(width 0.1)
				(type default)
			)
			(layer "B.Fab")
		)
		(fp_line
			(start 0.67945 0.3048)
			(end 0.67945 -0.305054)
			(stroke
				(width 0.1)
				(type default)
			)
			(layer "B.Fab")
		)
		(fp_line
			(start -0.120396 0.2794)
			(end 0.12065 0.2794)
			(stroke
				(width 0.1)
				(type default)
			)
			(layer "B.Fab")
		)
		(fp_line
			(start 0.12065 0.2794)
			(end 0.12065 0.3048)
			(stroke
				(width 0.1)
				(type default)
			)
			(layer "B.Fab")
		)
		(fp_line
			(start -0.12065 -0.2794)
			(end -0.12065 -0.3048)
			(stroke
				(width 0.1)
				(type default)
			)
			(layer "B.Fab")
		)
		(fp_line
			(start 0.12065 -0.2794)
			(end -0.12065 -0.2794)
			(stroke
				(width 0.1)
				(type default)
			)
			(layer "B.Fab")
		)
		(fp_line
			(start -0.67945 -0.3048)
			(end -0.67945 0.3048)
			(stroke
				(width 0.1)
				(type default)
			)
			(layer "B.Fab")
		)
		(fp_line
			(start -0.12065 -0.3048)
			(end -0.67945 -0.3048)
			(stroke
				(width 0.1)
				(type default)
			)
			(layer "B.Fab")
		)
		(fp_line
			(start 0.12065 -0.305054)
			(end 0.12065 -0.2794)
			(stroke
				(width 0.1)
				(type default)
			)
			(layer "B.Fab")
		)
		(fp_line
			(start 0.67945 -0.305054)
			(end 0.12065 -0.305054)
			(stroke
				(width 0.1)
				(type default)
			)
			(layer "B.Fab")
		)
		(pad "1" smd circle
			(at 0.40005 0 90)
			(size 0 0)
			(layers "B.Cu" "B.Mask" "B.Paste")
			(net "VCCIO3")
		)
		(pad "2" smd circle
			(at -0.40005 0 90)
			(size 0 0)
			(layers "B.Cu" "B.Mask" "B.Paste")
			(net "GND")
		)
	)
	(footprint ""
		(layer "B.Cu")
		(at 76.982828 -47.21479)
		(property "Reference" "R8"
			(at 0 0 0)
			(layer "B.SilkS")
			(hide yes)
			(effects
				(font
					(size 1.27 1.27)
				)
				(justify mirror)
			)
		)
		(property "Value" ""
			(at 0 0 0)
			(layer "B.Fab")
			(effects
				(font
					(size 1.27 1.27)
				)
				(justify mirror)
			)
		)
		(duplicate_pad_numbers_are_jumpers no)
		(fp_line
			(start -0.7874 -0.4064)
			(end -0.7874 0.4064)
			(stroke
				(width 0.1524)
				(type default)
			)
			(layer "B.SilkS")
		)
		(fp_line
			(start -0.7874 0.4064)
			(end 0.487172 0.4064)
			(stroke
				(width 0.1524)
				(type default)
			)
			(layer "B.SilkS")
		)
		(fp_line
			(start 0.7874 -0.4064)
			(end -0.7874 -0.4064)
			(stroke
				(width 0.1524)
				(type default)
			)
			(layer "B.SilkS")
		)
		(fp_line
			(start 0.7874 0.09779)
			(end 0.7874 -0.4064)
			(stroke
				(width 0.1524)
				(type default)
			)
			(layer "B.SilkS")
		)
		(fp_line
			(start -0.67945 -0.3048)
			(end -0.67945 0.3048)
			(stroke
				(width 0.1)
				(type default)
			)
			(layer "B.Fab")
		)
		(fp_line
			(start -0.67945 0.3048)
			(end -0.120396 0.3048)
			(stroke
				(width 0.1)
				(type default)
			)
			(layer "B.Fab")
		)
		(fp_line
			(start -0.12065 -0.3048)
			(end -0.67945 -0.3048)
			(stroke
				(width 0.1)
				(type default)
			)
			(layer "B.Fab")
		)
		(fp_line
			(start -0.12065 -0.2794)
			(end -0.12065 -0.3048)
			(stroke
				(width 0.1)
				(type default)
			)
			(layer "B.Fab")
		)
		(fp_line
			(start -0.120396 0.2794)
			(end 0.12065 0.2794)
			(stroke
				(width 0.1)
				(type default)
			)
			(layer "B.Fab")
		)
		(fp_line
			(start -0.120396 0.3048)
			(end -0.120396 0.2794)
			(stroke
				(width 0.1)
				(type default)
			)
			(layer "B.Fab")
		)
		(fp_line
			(start 0.12065 -0.305054)
			(end 0.12065 -0.2794)
			(stroke
				(width 0.1)
				(type default)
			)
			(layer "B.Fab")
		)
		(fp_line
			(start 0.12065 -0.2794)
			(end -0.12065 -0.2794)
			(stroke
				(width 0.1)
				(type default)
			)
			(layer "B.Fab")
		)
		(fp_line
			(start 0.12065 0.2794)
			(end 0.12065 0.3048)
			(stroke
				(width 0.1)
				(type default)
			)
			(layer "B.Fab")
		)
		(fp_line
			(start 0.12065 0.3048)
			(end 0.67945 0.3048)
			(stroke
				(width 0.1)
				(type default)
			)
			(layer "B.Fab")
		)
		(fp_line
			(start 0.67945 -0.305054)
			(end 0.12065 -0.305054)
			(stroke
				(width 0.1)
				(type default)
			)
			(layer "B.Fab")
		)
		(fp_line
			(start 0.67945 0.3048)
			(end 0.67945 -0.305054)
			(stroke
				(width 0.1)
				(type default)
			)
			(layer "B.Fab")
		)
		(pad "1" smd circle
			(at 0.40005 0 180)
			(size 0 0)
			(layers "B.Cu" "B.Mask" "B.Paste")
			(net "M_BMC_DDR4_MCLK_DP")
		)
		(pad "2" smd circle
			(at -0.40005 0 180)
			(size 0 0)
			(layers "B.Cu" "B.Mask" "B.Paste")
			(net "M_BMC_DDR4_MCLK_C")
		)
	)
	(footprint ""
		(layer "B.Cu")
		(at 18.415 -17.907 90)
		(property "Reference" "R410"
			(at 0 0 90)
			(layer "B.SilkS")
			(hide yes)
			(effects
				(font
					(size 1.27 1.27)
				)
				(justify mirror)
			)
		)
		(property "Value" ""
			(at 0 0 90)
			(layer "B.Fab")
			(effects
				(font
					(size 1.27 1.27)
				)
				(justify mirror)
			)
		)
		(duplicate_pad_numbers_are_jumpers no)
		(fp_line
			(start 0.7874 -0.4064)
			(end -0.7874 -0.4064)
			(stroke
				(width 0.1524)
				(type default)
			)
			(layer "B.SilkS")
		)
		(fp_line
			(start -0.7874 -0.4064)
			(end -0.7874 0.4064)
			(stroke
				(width 0.1524)
				(type default)
			)
			(layer "B.SilkS")
		)
		(fp_line
			(start 0.7874 0.4064)
			(end 0.7874 -0.4064)
			(stroke
				(width 0.1524)
				(type default)
			)
			(layer "B.SilkS")
		)
		(fp_line
			(start -0.7874 0.4064)
			(end 0.7874 0.4064)
			(stroke
				(width 0.1524)
				(type default)
			)
			(layer "B.SilkS")
		)
		(fp_line
			(start 0.67945 -0.305054)
			(end 0.12065 -0.305054)
			(stroke
				(width 0.1)
				(type default)
			)
			(layer "B.Fab")
		)
		(fp_line
			(start 0.12065 -0.305054)
			(end 0.12065 -0.2794)
			(stroke
				(width 0.1)
				(type default)
			)
			(layer "B.Fab")
		)
		(fp_line
			(start -0.12065 -0.3048)
			(end -0.67945 -0.3048)
			(stroke
				(width 0.1)
				(type default)
			)
			(layer "B.Fab")
		)
		(fp_line
			(start -0.67945 -0.3048)
			(end -0.67945 0.3048)
			(stroke
				(width 0.1)
				(type default)
			)
			(layer "B.Fab")
		)
		(fp_line
			(start 0.12065 -0.2794)
			(end -0.12065 -0.2794)
			(stroke
				(width 0.1)
				(type default)
			)
			(layer "B.Fab")
		)
		(fp_line
			(start -0.12065 -0.2794)
			(end -0.12065 -0.3048)
			(stroke
				(width 0.1)
				(type default)
			)
			(layer "B.Fab")
		)
		(fp_line
			(start 0.12065 0.2794)
			(end 0.12065 0.3048)
			(stroke
				(width 0.1)
				(type default)
			)
			(layer "B.Fab")
		)
		(fp_line
			(start -0.120396 0.2794)
			(end 0.12065 0.2794)
			(stroke
				(width 0.1)
				(type default)
			)
			(layer "B.Fab")
		)
		(fp_line
			(start 0.67945 0.3048)
			(end 0.67945 -0.305054)
			(stroke
				(width 0.1)
				(type default)
			)
			(layer "B.Fab")
		)
		(fp_line
			(start 0.12065 0.3048)
			(end 0.67945 0.3048)
			(stroke
				(width 0.1)
				(type default)
			)
			(layer "B.Fab")
		)
		(fp_line
			(start -0.120396 0.3048)
			(end -0.120396 0.2794)
			(stroke
				(width 0.1)
				(type default)
			)
			(layer "B.Fab")
		)
		(fp_line
			(start -0.67945 0.3048)
			(end -0.120396 0.3048)
			(stroke
				(width 0.1)
				(type default)
			)
			(layer "B.Fab")
		)
		(pad "1" smd circle
			(at 0.40005 0 270)
			(size 0 0)
			(layers "B.Cu" "B.Mask" "B.Paste")
			(net "SMB_TMP421_BMC_MM2_SCL")
		)
		(pad "2" smd circle
			(at -0.40005 0 270)
			(size 0 0)
			(layers "B.Cu" "B.Mask" "B.Paste")
			(net "SMB_BMC_MM2_SCL")
		)
	)
)
